(kicad_pcb
	(version 20260206)
	(generator "pcbnew")
	(generator_version "10.0")
	(general
		(thickness 1.6)
		(legacy_teardrops no)
	)
	(paper "A4")
	(title_block
		(title "01162023_DA0F0TEBIF0_F0T_Expander_BD_F_brd_V02_OCP.brd")
		(comment 1 "Grand Teton / footprints 3094-3099 of 9728")
	)
	(layers
		(0 "F.Cu" signal "TOP")
		(4 "In1.Cu" signal "GND")
		(6 "In2.Cu" signal "VCC")
		(8 "In3.Cu" signal "VCC1")
		(10 "In4.Cu" signal "GND1")
		(12 "In5.Cu" signal "IN1")
		(14 "In6.Cu" signal "GND2")
		(16 "In7.Cu" signal "IN2")
		(18 "In8.Cu" signal "GND3")
		(20 "In9.Cu" signal "IN3")
		(22 "In10.Cu" signal "GND4")
		(24 "In11.Cu" signal "IN4")
		(26 "In12.Cu" signal "GND5")
		(28 "In13.Cu" signal "IN5")
		(30 "In14.Cu" signal "GND6")
		(32 "In15.Cu" signal "IN6")
		(34 "In16.Cu" signal "GND7")
		(2 "B.Cu" signal "BOTTOM")
		(9 "F.Adhes" user "F.Adhesive")
		(11 "B.Adhes" user "B.Adhesive")
		(13 "F.Paste" user "Package Geometry/Pastemask Top")
		(15 "B.Paste" user "Package Geometry/Pastemask Bottom")
		(5 "F.SilkS" user "Ref Des/Silkscreen Top")
		(7 "B.SilkS" user "Ref Des/Silkscreen Bottom")
		(1 "F.Mask" user "Board Geometry/Soldermask Top")
		(3 "B.Mask" user "Board Geometry/Soldermask Bottom")
		(17 "Dwgs.User" user "User.Drawings")
		(19 "Cmts.User" user "User.Comments")
		(21 "Eco1.User" user "User.Eco1")
		(23 "Eco2.User" user "User.Eco2")
		(25 "Edge.Cuts" user "Board Geometry/Outline")
		(27 "Margin" user)
		(31 "F.CrtYd" user "Package Geometry/Place Bound Top")
		(29 "B.CrtYd" user "Package Geometry/Place Bound Bottom")
		(35 "F.Fab" user "Ref Des/Assembly Top")
		(33 "B.Fab" user "Ref Des/Assembly Bottom")
	)
	(footprint ""
		(layer "F.Cu")
		(at 395.247368 -19.33956)
		(property "Reference" "C3967"
			(at 0 0 0)
			(layer "F.SilkS")
			(hide yes)
			(effects
				(font
					(size 1.27 1.27)
				)
			)
		)
		(property "Value" ""
			(at 0 0 0)
			(layer "F.Fab")
			(effects
				(font
					(size 1.27 1.27)
				)
			)
		)
		(duplicate_pad_numbers_are_jumpers no)
		(fp_line
			(start -0.7874 -0.4064)
			(end 0.7874 -0.4064)
			(stroke
				(width 0.1524)
				(type default)
			)
			(layer "F.SilkS")
		)
		(fp_line
			(start -0.7874 0.4064)
			(end -0.7874 -0.4064)
			(stroke
				(width 0.1524)
				(type default)
			)
			(layer "F.SilkS")
		)
		(fp_line
			(start 0.7874 -0.4064)
			(end 0.7874 0.4064)
			(stroke
				(width 0.1524)
				(type default)
			)
			(layer "F.SilkS")
		)
		(fp_line
			(start 0.7874 0.4064)
			(end -0.7874 0.4064)
			(stroke
				(width 0.1524)
				(type default)
			)
			(layer "F.SilkS")
		)
		(fp_line
			(start -0.67945 -0.305054)
			(end -0.12065 -0.305054)
			(stroke
				(width 0.1)
				(type default)
			)
			(layer "F.Fab")
		)
		(fp_line
			(start -0.67945 0.3048)
			(end -0.67945 -0.305054)
			(stroke
				(width 0.1)
				(type default)
			)
			(layer "F.Fab")
		)
		(fp_line
			(start -0.12065 -0.305054)
			(end -0.12065 -0.2794)
			(stroke
				(width 0.1)
				(type default)
			)
			(layer "F.Fab")
		)
		(fp_line
			(start -0.12065 -0.2794)
			(end 0.12065 -0.2794)
			(stroke
				(width 0.1)
				(type default)
			)
			(layer "F.Fab")
		)
		(fp_line
			(start -0.12065 0.2794)
			(end -0.12065 0.3048)
			(stroke
				(width 0.1)
				(type default)
			)
			(layer "F.Fab")
		)
		(fp_line
			(start -0.12065 0.3048)
			(end -0.67945 0.3048)
			(stroke
				(width 0.1)
				(type default)
			)
			(layer "F.Fab")
		)
		(fp_line
			(start 0.120396 0.2794)
			(end -0.12065 0.2794)
			(stroke
				(width 0.1)
				(type default)
			)
			(layer "F.Fab")
		)
		(fp_line
			(start 0.120396 0.3048)
			(end 0.120396 0.2794)
			(stroke
				(width 0.1)
				(type default)
			)
			(layer "F.Fab")
		)
		(fp_line
			(start 0.12065 -0.3048)
			(end 0.67945 -0.3048)
			(stroke
				(width 0.1)
				(type default)
			)
			(layer "F.Fab")
		)
		(fp_line
			(start 0.12065 -0.2794)
			(end 0.12065 -0.3048)
			(stroke
				(width 0.1)
				(type default)
			)
			(layer "F.Fab")
		)
		(fp_line
			(start 0.67945 -0.3048)
			(end 0.67945 0.3048)
			(stroke
				(width 0.1)
				(type default)
			)
			(layer "F.Fab")
		)
		(fp_line
			(start 0.67945 0.3048)
			(end 0.120396 0.3048)
			(stroke
				(width 0.1)
				(type default)
			)
			(layer "F.Fab")
		)
		(pad "1" smd circle
			(at -0.40005 0)
			(size 0 0)
			(layers "F.Cu" "F.Mask" "F.Paste")
			(net "P12V_SSD13")
		)
		(pad "2" smd circle
			(at 0.40005 0)
			(size 0 0)
			(layers "F.Cu" "F.Mask" "F.Paste")
			(net "GND")
		)
	)
	(footprint ""
		(layer "F.Cu")
		(at 369.495578 -90.642694)
		(property "Reference" "R1609"
			(at 0 0 0)
			(layer "F.SilkS")
			(hide yes)
			(effects
				(font
					(size 1.27 1.27)
				)
			)
		)
		(property "Value" ""
			(at 0 0 0)
			(layer "F.Fab")
			(effects
				(font
					(size 1.27 1.27)
				)
			)
		)
		(duplicate_pad_numbers_are_jumpers no)
		(fp_line
			(start -0.7874 -0.4064)
			(end 0.7874 -0.4064)
			(stroke
				(width 0.1524)
				(type default)
			)
			(layer "F.SilkS")
		)
		(fp_line
			(start -0.7874 0.4064)
			(end -0.7874 -0.4064)
			(stroke
				(width 0.1524)
				(type default)
			)
			(layer "F.SilkS")
		)
		(fp_line
			(start 0.7874 -0.4064)
			(end 0.7874 0.4064)
			(stroke
				(width 0.1524)
				(type default)
			)
			(layer "F.SilkS")
		)
		(fp_line
			(start 0.7874 0.4064)
			(end -0.7874 0.4064)
			(stroke
				(width 0.1524)
				(type default)
			)
			(layer "F.SilkS")
		)
		(fp_line
			(start -0.67945 -0.305054)
			(end -0.12065 -0.305054)
			(stroke
				(width 0.1)
				(type default)
			)
			(layer "F.Fab")
		)
		(fp_line
			(start -0.67945 0.3048)
			(end -0.67945 -0.305054)
			(stroke
				(width 0.1)
				(type default)
			)
			(layer "F.Fab")
		)
		(fp_line
			(start -0.12065 -0.305054)
			(end -0.12065 -0.2794)
			(stroke
				(width 0.1)
				(type default)
			)
			(layer "F.Fab")
		)
		(fp_line
			(start -0.12065 -0.2794)
			(end 0.12065 -0.2794)
			(stroke
				(width 0.1)
				(type default)
			)
			(layer "F.Fab")
		)
		(fp_line
			(start -0.12065 0.2794)
			(end -0.12065 0.3048)
			(stroke
				(width 0.1)
				(type default)
			)
			(layer "F.Fab")
		)
		(fp_line
			(start -0.12065 0.3048)
			(end -0.67945 0.3048)
			(stroke
				(width 0.1)
				(type default)
			)
			(layer "F.Fab")
		)
		(fp_line
			(start 0.120396 0.2794)
			(end -0.12065 0.2794)
			(stroke
				(width 0.1)
				(type default)
			)
			(layer "F.Fab")
		)
		(fp_line
			(start 0.120396 0.3048)
			(end 0.120396 0.2794)
			(stroke
				(width 0.1)
				(type default)
			)
			(layer "F.Fab")
		)
		(fp_line
			(start 0.12065 -0.3048)
			(end 0.67945 -0.3048)
			(stroke
				(width 0.1)
				(type default)
			)
			(layer "F.Fab")
		)
		(fp_line
			(start 0.12065 -0.2794)
			(end 0.12065 -0.3048)
			(stroke
				(width 0.1)
				(type default)
			)
			(layer "F.Fab")
		)
		(fp_line
			(start 0.67945 -0.3048)
			(end 0.67945 0.3048)
			(stroke
				(width 0.1)
				(type default)
			)
			(layer "F.Fab")
		)
		(fp_line
			(start 0.67945 0.3048)
			(end 0.120396 0.3048)
			(stroke
				(width 0.1)
				(type default)
			)
			(layer "F.Fab")
		)
		(pad "1" smd circle
			(at -0.40005 0)
			(size 0 0)
			(layers "F.Cu" "F.Mask" "F.Paste")
			(net "BIC_I2C9_SSD_MUX1_A2")
		)
		(pad "2" smd circle
			(at 0.40005 0)
			(size 0 0)
			(layers "F.Cu" "F.Mask" "F.Paste")
			(net "GND")
		)
	)
	(footprint ""
		(layer "F.Cu")
		(at 444.247016 -55.63489 90)
		(property "Reference" "PC894"
			(at 0 0 90)
			(layer "F.SilkS")
			(hide yes)
			(effects
				(font
					(size 1.27 1.27)
				)
			)
		)
		(property "Value" ""
			(at 0 0 90)
			(layer "F.Fab")
			(effects
				(font
					(size 1.27 1.27)
				)
			)
		)
		(duplicate_pad_numbers_are_jumpers no)
		(fp_line
			(start 1.524 -0.762)
			(end 1.524 0.762)
			(stroke
				(width 0.1524)
				(type default)
			)
			(layer "F.SilkS")
		)
		(fp_line
			(start -1.524 -0.762)
			(end 1.524 -0.762)
			(stroke
				(width 0.1524)
				(type default)
			)
			(layer "F.SilkS")
		)
		(fp_line
			(start 1.524 0.762)
			(end -1.524 0.762)
			(stroke
				(width 0.1524)
				(type default)
			)
			(layer "F.SilkS")
		)
		(fp_line
			(start -1.524 0.762)
			(end -1.524 -0.762)
			(stroke
				(width 0.1524)
				(type default)
			)
			(layer "F.SilkS")
		)
		(fp_line
			(start 1.1049 -0.724916)
			(end -1.1049 -0.724916)
			(stroke
				(width 0.1)
				(type default)
			)
			(layer "F.Fab")
		)
		(fp_line
			(start -1.1049 -0.724916)
			(end -1.1049 0.724916)
			(stroke
				(width 0.1)
				(type default)
			)
			(layer "F.Fab")
		)
		(fp_line
			(start 1.1049 0.724916)
			(end 1.1049 -0.724916)
			(stroke
				(width 0.1)
				(type default)
			)
			(layer "F.Fab")
		)
		(fp_line
			(start -1.1049 0.724916)
			(end 1.1049 0.724916)
			(stroke
				(width 0.1)
				(type default)
			)
			(layer "F.Fab")
		)
		(pad "1" smd rect
			(at -0.889 0 270)
			(size 1.016 1.27)
			(layers "F.Cu" "F.Mask" "F.Paste")
			(net "P12V_SSD15_R")
		)
		(pad "2" smd rect
			(at 0.889 0 270)
			(size 1.016 1.27)
			(layers "F.Cu" "F.Mask" "F.Paste")
			(net "GND")
		)
	)
	(footprint ""
		(layer "F.Cu")
		(at 324.25005 -306.074572 90)
		(property "Reference" "R1376"
			(at 0 0 90)
			(layer "F.SilkS")
			(hide yes)
			(effects
				(font
					(size 1.27 1.27)
				)
			)
		)
		(property "Value" ""
			(at 0 0 90)
			(layer "F.Fab")
			(effects
				(font
					(size 1.27 1.27)
				)
			)
		)
		(duplicate_pad_numbers_are_jumpers no)
		(fp_line
			(start 0.7874 -0.4064)
			(end 0.7874 0.4064)
			(stroke
				(width 0.1524)
				(type default)
			)
			(layer "F.SilkS")
		)
		(fp_line
			(start -0.7874 -0.4064)
			(end 0.7874 -0.4064)
			(stroke
				(width 0.1524)
				(type default)
			)
			(layer "F.SilkS")
		)
		(fp_line
			(start 0.7874 0.4064)
			(end -0.7874 0.4064)
			(stroke
				(width 0.1524)
				(type default)
			)
			(layer "F.SilkS")
		)
		(fp_line
			(start -0.7874 0.4064)
			(end -0.7874 -0.4064)
			(stroke
				(width 0.1524)
				(type default)
			)
			(layer "F.SilkS")
		)
		(fp_line
			(start -0.12065 -0.305054)
			(end -0.12065 -0.2794)
			(stroke
				(width 0.1)
				(type default)
			)
			(layer "F.Fab")
		)
		(fp_line
			(start -0.67945 -0.305054)
			(end -0.12065 -0.305054)
			(stroke
				(width 0.1)
				(type default)
			)
			(layer "F.Fab")
		)
		(fp_line
			(start 0.67945 -0.3048)
			(end 0.67945 0.3048)
			(stroke
				(width 0.1)
				(type default)
			)
			(layer "F.Fab")
		)
		(fp_line
			(start 0.12065 -0.3048)
			(end 0.67945 -0.3048)
			(stroke
				(width 0.1)
				(type default)
			)
			(layer "F.Fab")
		)
		(fp_line
			(start 0.12065 -0.2794)
			(end 0.12065 -0.3048)
			(stroke
				(width 0.1)
				(type default)
			)
			(layer "F.Fab")
		)
		(fp_line
			(start -0.12065 -0.2794)
			(end 0.12065 -0.2794)
			(stroke
				(width 0.1)
				(type default)
			)
			(layer "F.Fab")
		)
		(fp_line
			(start 0.120396 0.2794)
			(end -0.12065 0.2794)
			(stroke
				(width 0.1)
				(type default)
			)
			(layer "F.Fab")
		)
		(fp_line
			(start -0.12065 0.2794)
			(end -0.12065 0.3048)
			(stroke
				(width 0.1)
				(type default)
			)
			(layer "F.Fab")
		)
		(fp_line
			(start 0.67945 0.3048)
			(end 0.120396 0.3048)
			(stroke
				(width 0.1)
				(type default)
			)
			(layer "F.Fab")
		)
		(fp_line
			(start 0.120396 0.3048)
			(end 0.120396 0.2794)
			(stroke
				(width 0.1)
				(type default)
			)
			(layer "F.Fab")
		)
		(fp_line
			(start -0.12065 0.3048)
			(end -0.67945 0.3048)
			(stroke
				(width 0.1)
				(type default)
			)
			(layer "F.Fab")
		)
		(fp_line
			(start -0.67945 0.3048)
			(end -0.67945 -0.305054)
			(stroke
				(width 0.1)
				(type default)
			)
			(layer "F.Fab")
		)
		(pad "1" smd circle
			(at -0.40005 0 90)
			(size 0 0)
			(layers "F.Cu" "F.Mask" "F.Paste")
			(net "PEX2_SPARE6")
		)
		(pad "2" smd circle
			(at 0.40005 0 90)
			(size 0 0)
			(layers "F.Cu" "F.Mask" "F.Paste")
			(net "P1V8_PEX")
		)
	)
	(footprint ""
		(layer "F.Cu")
		(at 333.502 -201.168 -90)
		(property "Reference" "R4115"
			(at 0 0 270)
			(layer "F.SilkS")
			(hide yes)
			(effects
				(font
					(size 1.27 1.27)
				)
			)
		)
		(property "Value" ""
			(at 0 0 270)
			(layer "F.Fab")
			(effects
				(font
					(size 1.27 1.27)
				)
			)
		)
		(duplicate_pad_numbers_are_jumpers no)
		(fp_line
			(start -0.7874 0.4064)
			(end -0.7874 -0.4064)
			(stroke
				(width 0.1524)
				(type default)
			)
			(layer "F.SilkS")
		)
		(fp_line
			(start 0.7874 0.4064)
			(end -0.7874 0.4064)
			(stroke
				(width 0.1524)
				(type default)
			)
			(layer "F.SilkS")
		)
		(fp_line
			(start -0.7874 -0.4064)
			(end 0.7874 -0.4064)
			(stroke
				(width 0.1524)
				(type default)
			)
			(layer "F.SilkS")
		)
		(fp_line
			(start 0.7874 -0.4064)
			(end 0.7874 0.4064)
			(stroke
				(width 0.1524)
				(type default)
			)
			(layer "F.SilkS")
		)
		(fp_line
			(start -0.67945 0.3048)
			(end -0.67945 -0.305054)
			(stroke
				(width 0.1)
				(type default)
			)
			(layer "F.Fab")
		)
		(fp_line
			(start -0.12065 0.3048)
			(end -0.67945 0.3048)
			(stroke
				(width 0.1)
				(type default)
			)
			(layer "F.Fab")
		)
		(fp_line
			(start 0.120396 0.3048)
			(end 0.120396 0.2794)
			(stroke
				(width 0.1)
				(type default)
			)
			(layer "F.Fab")
		)
		(fp_line
			(start 0.67945 0.3048)
			(end 0.120396 0.3048)
			(stroke
				(width 0.1)
				(type default)
			)
			(layer "F.Fab")
		)
		(fp_line
			(start -0.12065 0.2794)
			(end -0.12065 0.3048)
			(stroke
				(width 0.1)
				(type default)
			)
			(layer "F.Fab")
		)
		(fp_line
			(start 0.120396 0.2794)
			(end -0.12065 0.2794)
			(stroke
				(width 0.1)
				(type default)
			)
			(layer "F.Fab")
		)
		(fp_line
			(start -0.12065 -0.2794)
			(end 0.12065 -0.2794)
			(stroke
				(width 0.1)
				(type default)
			)
			(layer "F.Fab")
		)
		(fp_line
			(start 0.12065 -0.2794)
			(end 0.12065 -0.3048)
			(stroke
				(width 0.1)
				(type default)
			)
			(layer "F.Fab")
		)
		(fp_line
			(start 0.12065 -0.3048)
			(end 0.67945 -0.3048)
			(stroke
				(width 0.1)
				(type default)
			)
			(layer "F.Fab")
		)
		(fp_line
			(start 0.67945 -0.3048)
			(end 0.67945 0.3048)
			(stroke
				(width 0.1)
				(type default)
			)
			(layer "F.Fab")
		)
		(fp_line
			(start -0.67945 -0.305054)
			(end -0.12065 -0.305054)
			(stroke
				(width 0.1)
				(type default)
			)
			(layer "F.Fab")
		)
		(fp_line
			(start -0.12065 -0.305054)
			(end -0.12065 -0.2794)
			(stroke
				(width 0.1)
				(type default)
			)
			(layer "F.Fab")
		)
		(pad "1" smd circle
			(at -0.40005 0 270)
			(size 0 0)
			(layers "F.Cu" "F.Mask" "F.Paste")
			(net "SSD8_PWR_EN")
		)
		(pad "2" smd circle
			(at 0.40005 0 270)
			(size 0 0)
			(layers "F.Cu" "F.Mask" "F.Paste")
			(net "SSD8_PWR_EN_R")
		)
	)
	(footprint ""
		(layer "F.Cu")
		(at 373.641874 -261.026402 180)
		(property "Reference" "C3592"
			(at 0 0 180)
			(layer "F.SilkS")
			(hide yes)
			(effects
				(font
					(size 1.27 1.27)
				)
			)
		)
		(property "Value" ""
			(at 0 0 180)
			(layer "F.Fab")
			(effects
				(font
					(size 1.27 1.27)
				)
			)
		)
		(duplicate_pad_numbers_are_jumpers no)
		(fp_line
			(start 1.2954 0.5842)
			(end -1.2954 0.5842)
			(stroke
				(width 0.1524)
				(type default)
			)
			(layer "F.SilkS")
		)
		(fp_line
			(start 1.2954 -0.5842)
			(end 1.2954 0.5842)
			(stroke
				(width 0.1524)
				(type default)
			)
			(layer "F.SilkS")
		)
		(fp_line
			(start -1.2954 0.5842)
			(end -1.2954 -0.5842)
			(stroke
				(width 0.1524)
				(type default)
			)
			(layer "F.SilkS")
		)
		(fp_line
			(start -1.2954 -0.5842)
			(end 1.2954 -0.5842)
			(stroke
				(width 0.1524)
				(type default)
			)
			(layer "F.SilkS")
		)
		(fp_line
			(start 1.1938 0.4064)
			(end 0.8636 0.4064)
			(stroke
				(width 0.1)
				(type default)
			)
			(layer "F.Fab")
		)
		(fp_line
			(start 1.1938 -0.4064)
			(end 1.1938 0.4064)
			(stroke
				(width 0.1)
				(type default)
			)
			(layer "F.Fab")
		)
		(fp_line
			(start 0.8636 0.4572)
			(end -0.8636 0.4572)
			(stroke
				(width 0.1)
				(type default)
			)
			(layer "F.Fab")
		)
		(fp_line
			(start 0.8636 0.4064)
			(end 0.8636 0.4572)
			(stroke
				(width 0.1)
				(type default)
			)
			(layer "F.Fab")
		)
		(fp_line
			(start 0.8636 -0.4064)
			(end 1.1938 -0.4064)
			(stroke
				(width 0.1)
				(type default)
			)
			(layer "F.Fab")
		)
		(fp_line
			(start 0.8636 -0.4572)
			(end 0.8636 -0.4064)
			(stroke
				(width 0.1)
				(type default)
			)
			(layer "F.Fab")
		)
		(fp_line
			(start -0.8636 0.4572)
			(end -0.8636 0.4064)
			(stroke
				(width 0.1)
				(type default)
			)
			(layer "F.Fab")
		)
		(fp_line
			(start -0.8636 0.4064)
			(end -1.1938 0.4064)
			(stroke
				(width 0.1)
				(type default)
			)
			(layer "F.Fab")
		)
		(fp_line
			(start -0.8636 -0.4064)
			(end -0.8636 -0.4572)
			(stroke
				(width 0.1)
				(type default)
			)
			(layer "F.Fab")
		)
		(fp_line
			(start -0.8636 -0.4572)
			(end 0.8636 -0.4572)
			(stroke
				(width 0.1)
				(type default)
			)
			(layer "F.Fab")
		)
		(fp_line
			(start -1.1938 0.4064)
			(end -1.1938 -0.4064)
			(stroke
				(width 0.1)
				(type default)
			)
			(layer "F.Fab")
		)
		(fp_line
			(start -1.1938 -0.4064)
			(end -0.8636 -0.4064)
			(stroke
				(width 0.1)
				(type default)
			)
			(layer "F.Fab")
		)
		(pad "1" smd rect
			(at -0.7366 0 90)
			(size 0.7112 0.8128)
			(layers "F.Cu" "F.Mask" "F.Paste")
			(net "P1V8_VDDA_PEX3")
		)
		(pad "2" smd rect
			(at 0.7366 0 90)
			(size 0.7112 0.8128)
			(layers "F.Cu" "F.Mask" "F.Paste")
			(net "GND")
		)
	)
)
